(kicad_pcb
	(version 20260206)
	(generator "pcbnew")
	(generator_version "10.0")
	(general
		(thickness 1.6)
		(legacy_teardrops no)
	)
	(paper "A4")
	(title_block
		(title "01162023_DA0F0TEBIF0_F0T_Expander_BD_F_brd_V02_OCP.brd")
		(comment 1 "Grand Teton / footprints 8925-8931 of 9728")
	)
	(layers
		(0 "F.Cu" signal "TOP")
		(4 "In1.Cu" signal "GND")
		(6 "In2.Cu" signal "VCC")
		(8 "In3.Cu" signal "VCC1")
		(10 "In4.Cu" signal "GND1")
		(12 "In5.Cu" signal "IN1")
		(14 "In6.Cu" signal "GND2")
		(16 "In7.Cu" signal "IN2")
		(18 "In8.Cu" signal "GND3")
		(20 "In9.Cu" signal "IN3")
		(22 "In10.Cu" signal "GND4")
		(24 "In11.Cu" signal "IN4")
		(26 "In12.Cu" signal "GND5")
		(28 "In13.Cu" signal "IN5")
		(30 "In14.Cu" signal "GND6")
		(32 "In15.Cu" signal "IN6")
		(34 "In16.Cu" signal "GND7")
		(2 "B.Cu" signal "BOTTOM")
		(9 "F.Adhes" user "F.Adhesive")
		(11 "B.Adhes" user "B.Adhesive")
		(13 "F.Paste" user "Package Geometry/Pastemask Top")
		(15 "B.Paste" user "Package Geometry/Pastemask Bottom")
		(5 "F.SilkS" user "Ref Des/Silkscreen Top")
		(7 "B.SilkS" user "Ref Des/Silkscreen Bottom")
		(1 "F.Mask" user "Board Geometry/Soldermask Top")
		(3 "B.Mask" user "Board Geometry/Soldermask Bottom")
		(17 "Dwgs.User" user "User.Drawings")
		(19 "Cmts.User" user "User.Comments")
		(21 "Eco1.User" user "User.Eco1")
		(23 "Eco2.User" user "User.Eco2")
		(25 "Edge.Cuts" user "Board Geometry/Outline")
		(27 "Margin" user)
		(31 "F.CrtYd" user "Package Geometry/Place Bound Top")
		(29 "B.CrtYd" user "Package Geometry/Place Bound Bottom")
		(35 "F.Fab" user "Ref Des/Assembly Top")
		(33 "B.Fab" user "Ref Des/Assembly Bottom")
	)
	(footprint ""
		(layer "B.Cu")
		(at 300.872144 -112.421924 180)
		(property "Reference" "R264"
			(at 0 0 0)
			(layer "B.SilkS")
			(hide yes)
			(effects
				(font
					(size 1.27 1.27)
				)
				(justify mirror)
			)
		)
		(property "Value" ""
			(at 0 0 0)
			(layer "B.Fab")
			(effects
				(font
					(size 1.27 1.27)
				)
				(justify mirror)
			)
		)
		(duplicate_pad_numbers_are_jumpers no)
		(fp_line
			(start 0.7874 0.4064)
			(end 0.7874 -0.4064)
			(stroke
				(width 0.1524)
				(type default)
			)
			(layer "B.SilkS")
		)
		(fp_line
			(start 0.7874 -0.4064)
			(end -0.7874 -0.4064)
			(stroke
				(width 0.1524)
				(type default)
			)
			(layer "B.SilkS")
		)
		(fp_line
			(start -0.7874 0.4064)
			(end 0.7874 0.4064)
			(stroke
				(width 0.1524)
				(type default)
			)
			(layer "B.SilkS")
		)
		(fp_line
			(start -0.7874 -0.4064)
			(end -0.7874 0.4064)
			(stroke
				(width 0.1524)
				(type default)
			)
			(layer "B.SilkS")
		)
		(fp_line
			(start 0.67945 0.3048)
			(end 0.67945 -0.305054)
			(stroke
				(width 0.1)
				(type default)
			)
			(layer "B.Fab")
		)
		(fp_line
			(start 0.67945 -0.305054)
			(end 0.12065 -0.305054)
			(stroke
				(width 0.1)
				(type default)
			)
			(layer "B.Fab")
		)
		(fp_line
			(start 0.12065 0.3048)
			(end 0.67945 0.3048)
			(stroke
				(width 0.1)
				(type default)
			)
			(layer "B.Fab")
		)
		(fp_line
			(start 0.12065 0.2794)
			(end 0.12065 0.3048)
			(stroke
				(width 0.1)
				(type default)
			)
			(layer "B.Fab")
		)
		(fp_line
			(start 0.12065 -0.2794)
			(end -0.12065 -0.2794)
			(stroke
				(width 0.1)
				(type default)
			)
			(layer "B.Fab")
		)
		(fp_line
			(start 0.12065 -0.305054)
			(end 0.12065 -0.2794)
			(stroke
				(width 0.1)
				(type default)
			)
			(layer "B.Fab")
		)
		(fp_line
			(start -0.120396 0.3048)
			(end -0.120396 0.2794)
			(stroke
				(width 0.1)
				(type default)
			)
			(layer "B.Fab")
		)
		(fp_line
			(start -0.120396 0.2794)
			(end 0.12065 0.2794)
			(stroke
				(width 0.1)
				(type default)
			)
			(layer "B.Fab")
		)
		(fp_line
			(start -0.12065 -0.2794)
			(end -0.12065 -0.3048)
			(stroke
				(width 0.1)
				(type default)
			)
			(layer "B.Fab")
		)
		(fp_line
			(start -0.12065 -0.3048)
			(end -0.67945 -0.3048)
			(stroke
				(width 0.1)
				(type default)
			)
			(layer "B.Fab")
		)
		(fp_line
			(start -0.67945 0.3048)
			(end -0.120396 0.3048)
			(stroke
				(width 0.1)
				(type default)
			)
			(layer "B.Fab")
		)
		(fp_line
			(start -0.67945 -0.3048)
			(end -0.67945 0.3048)
			(stroke
				(width 0.1)
				(type default)
			)
			(layer "B.Fab")
		)
		(pad "1" smd circle
			(at 0.40005 0)
			(size 0 0)
			(layers "B.Cu" "B.Mask" "B.Paste")
			(net "SMB_NIC5_LS_SCL")
		)
		(pad "2" smd circle
			(at -0.40005 0)
			(size 0 0)
			(layers "B.Cu" "B.Mask" "B.Paste")
			(net "P3V3_NIC5")
		)
	)
	(footprint ""
		(layer "B.Cu")
		(at 394.65504 -295.2623)
		(property "Reference" "C3565"
			(at 0 0 0)
			(layer "B.SilkS")
			(hide yes)
			(effects
				(font
					(size 1.27 1.27)
				)
				(justify mirror)
			)
		)
		(property "Value" ""
			(at 0 0 0)
			(layer "B.Fab")
			(effects
				(font
					(size 1.27 1.27)
				)
				(justify mirror)
			)
		)
		(duplicate_pad_numbers_are_jumpers no)
		(fp_line
			(start -0.299974 -0.150114)
			(end -0.299974 0.150114)
			(stroke
				(width 0.1)
				(type default)
			)
			(layer "B.Fab")
		)
		(fp_line
			(start -0.299974 0.150114)
			(end 0.299974 0.150114)
			(stroke
				(width 0.1)
				(type default)
			)
			(layer "B.Fab")
		)
		(fp_line
			(start 0.299974 -0.150114)
			(end -0.299974 -0.150114)
			(stroke
				(width 0.1)
				(type default)
			)
			(layer "B.Fab")
		)
		(fp_line
			(start 0.299974 0.150114)
			(end 0.299974 -0.150114)
			(stroke
				(width 0.1)
				(type default)
			)
			(layer "B.Fab")
		)
		(pad "1" smd rect
			(at 0.2667 0 180)
			(size 0.3048 0.381)
			(layers "B.Cu" "B.Mask" "B.Paste")
			(net "PCEPLL4_VDDA18_PEX3")
		)
		(pad "2" smd rect
			(at -0.2667 0 180)
			(size 0.3048 0.381)
			(layers "B.Cu" "B.Mask" "B.Paste")
			(net "GND")
		)
	)
	(footprint ""
		(layer "B.Cu")
		(at 15.78356 -215.297258 180)
		(property "Reference" "R6568"
			(at 0 0 0)
			(layer "B.SilkS")
			(hide yes)
			(effects
				(font
					(size 1.27 1.27)
				)
				(justify mirror)
			)
		)
		(property "Value" ""
			(at 0 0 0)
			(layer "B.Fab")
			(effects
				(font
					(size 1.27 1.27)
				)
				(justify mirror)
			)
		)
		(duplicate_pad_numbers_are_jumpers no)
		(fp_line
			(start 0.7874 0.4064)
			(end 0.7874 -0.4064)
			(stroke
				(width 0.1524)
				(type default)
			)
			(layer "B.SilkS")
		)
		(fp_line
			(start 0.7874 -0.4064)
			(end -0.7874 -0.4064)
			(stroke
				(width 0.1524)
				(type default)
			)
			(layer "B.SilkS")
		)
		(fp_line
			(start -0.7874 0.4064)
			(end 0.7874 0.4064)
			(stroke
				(width 0.1524)
				(type default)
			)
			(layer "B.SilkS")
		)
		(fp_line
			(start -0.7874 -0.4064)
			(end -0.7874 0.4064)
			(stroke
				(width 0.1524)
				(type default)
			)
			(layer "B.SilkS")
		)
		(fp_line
			(start 0.67945 0.3048)
			(end 0.67945 -0.305054)
			(stroke
				(width 0.1)
				(type default)
			)
			(layer "B.Fab")
		)
		(fp_line
			(start 0.67945 -0.305054)
			(end 0.12065 -0.305054)
			(stroke
				(width 0.1)
				(type default)
			)
			(layer "B.Fab")
		)
		(fp_line
			(start 0.12065 0.3048)
			(end 0.67945 0.3048)
			(stroke
				(width 0.1)
				(type default)
			)
			(layer "B.Fab")
		)
		(fp_line
			(start 0.12065 0.2794)
			(end 0.12065 0.3048)
			(stroke
				(width 0.1)
				(type default)
			)
			(layer "B.Fab")
		)
		(fp_line
			(start 0.12065 -0.2794)
			(end -0.12065 -0.2794)
			(stroke
				(width 0.1)
				(type default)
			)
			(layer "B.Fab")
		)
		(fp_line
			(start 0.12065 -0.305054)
			(end 0.12065 -0.2794)
			(stroke
				(width 0.1)
				(type default)
			)
			(layer "B.Fab")
		)
		(fp_line
			(start -0.120396 0.3048)
			(end -0.120396 0.2794)
			(stroke
				(width 0.1)
				(type default)
			)
			(layer "B.Fab")
		)
		(fp_line
			(start -0.120396 0.2794)
			(end 0.12065 0.2794)
			(stroke
				(width 0.1)
				(type default)
			)
			(layer "B.Fab")
		)
		(fp_line
			(start -0.12065 -0.2794)
			(end -0.12065 -0.3048)
			(stroke
				(width 0.1)
				(type default)
			)
			(layer "B.Fab")
		)
		(fp_line
			(start -0.12065 -0.3048)
			(end -0.67945 -0.3048)
			(stroke
				(width 0.1)
				(type default)
			)
			(layer "B.Fab")
		)
		(fp_line
			(start -0.67945 0.3048)
			(end -0.120396 0.3048)
			(stroke
				(width 0.1)
				(type default)
			)
			(layer "B.Fab")
		)
		(fp_line
			(start -0.67945 -0.3048)
			(end -0.67945 0.3048)
			(stroke
				(width 0.1)
				(type default)
			)
			(layer "B.Fab")
		)
		(pad "1" smd circle
			(at 0.40005 0)
			(size 0 0)
			(layers "B.Cu" "B.Mask" "B.Paste")
			(net "P3V3_AUX")
		)
		(pad "2" smd circle
			(at -0.40005 0)
			(size 0 0)
			(layers "B.Cu" "B.Mask" "B.Paste")
			(net "PWRGD_PEX0_P1V8_PLL")
		)
	)
	(footprint ""
		(layer "B.Cu")
		(at 289.420046 -305.399948 -90)
		(property "Reference" "C3329"
			(at 0 0 90)
			(layer "B.SilkS")
			(hide yes)
			(effects
				(font
					(size 1.27 1.27)
				)
				(justify mirror)
			)
		)
		(property "Value" ""
			(at 0 0 90)
			(layer "B.Fab")
			(effects
				(font
					(size 1.27 1.27)
				)
				(justify mirror)
			)
		)
		(duplicate_pad_numbers_are_jumpers no)
		(fp_line
			(start -0.299974 0.150114)
			(end 0.299974 0.150114)
			(stroke
				(width 0.1)
				(type default)
			)
			(layer "B.Fab")
		)
		(fp_line
			(start 0.299974 0.150114)
			(end 0.299974 -0.150114)
			(stroke
				(width 0.1)
				(type default)
			)
			(layer "B.Fab")
		)
		(fp_line
			(start -0.299974 -0.150114)
			(end -0.299974 0.150114)
			(stroke
				(width 0.1)
				(type default)
			)
			(layer "B.Fab")
		)
		(fp_line
			(start 0.299974 -0.150114)
			(end -0.299974 -0.150114)
			(stroke
				(width 0.1)
				(type default)
			)
			(layer "B.Fab")
		)
		(pad "1" smd rect
			(at 0.2667 0 90)
			(size 0.3048 0.381)
			(layers "B.Cu" "B.Mask" "B.Paste")
			(net "P1V25_SERDES_VDDPLL_PEX2")
		)
		(pad "2" smd rect
			(at -0.2667 0 90)
			(size 0.3048 0.381)
			(layers "B.Cu" "B.Mask" "B.Paste")
			(net "GND")
		)
	)
	(footprint ""
		(layer "B.Cu")
		(at 409.897326 -110.497366)
		(property "Reference" "R390"
			(at 0 0 0)
			(layer "B.SilkS")
			(hide yes)
			(effects
				(font
					(size 1.27 1.27)
				)
				(justify mirror)
			)
		)
		(property "Value" ""
			(at 0 0 0)
			(layer "B.Fab")
			(effects
				(font
					(size 1.27 1.27)
				)
				(justify mirror)
			)
		)
		(duplicate_pad_numbers_are_jumpers no)
		(fp_line
			(start -0.7874 -0.4064)
			(end -0.7874 0.4064)
			(stroke
				(width 0.1524)
				(type default)
			)
			(layer "B.SilkS")
		)
		(fp_line
			(start -0.7874 0.4064)
			(end 0.7874 0.4064)
			(stroke
				(width 0.1524)
				(type default)
			)
			(layer "B.SilkS")
		)
		(fp_line
			(start 0.7874 -0.4064)
			(end -0.7874 -0.4064)
			(stroke
				(width 0.1524)
				(type default)
			)
			(layer "B.SilkS")
		)
		(fp_line
			(start 0.7874 0.4064)
			(end 0.7874 -0.4064)
			(stroke
				(width 0.1524)
				(type default)
			)
			(layer "B.SilkS")
		)
		(fp_line
			(start -0.67945 -0.3048)
			(end -0.67945 0.3048)
			(stroke
				(width 0.1)
				(type default)
			)
			(layer "B.Fab")
		)
		(fp_line
			(start -0.67945 0.3048)
			(end -0.120396 0.3048)
			(stroke
				(width 0.1)
				(type default)
			)
			(layer "B.Fab")
		)
		(fp_line
			(start -0.12065 -0.3048)
			(end -0.67945 -0.3048)
			(stroke
				(width 0.1)
				(type default)
			)
			(layer "B.Fab")
		)
		(fp_line
			(start -0.12065 -0.2794)
			(end -0.12065 -0.3048)
			(stroke
				(width 0.1)
				(type default)
			)
			(layer "B.Fab")
		)
		(fp_line
			(start -0.120396 0.2794)
			(end 0.12065 0.2794)
			(stroke
				(width 0.1)
				(type default)
			)
			(layer "B.Fab")
		)
		(fp_line
			(start -0.120396 0.3048)
			(end -0.120396 0.2794)
			(stroke
				(width 0.1)
				(type default)
			)
			(layer "B.Fab")
		)
		(fp_line
			(start 0.12065 -0.305054)
			(end 0.12065 -0.2794)
			(stroke
				(width 0.1)
				(type default)
			)
			(layer "B.Fab")
		)
		(fp_line
			(start 0.12065 -0.2794)
			(end -0.12065 -0.2794)
			(stroke
				(width 0.1)
				(type default)
			)
			(layer "B.Fab")
		)
		(fp_line
			(start 0.12065 0.2794)
			(end 0.12065 0.3048)
			(stroke
				(width 0.1)
				(type default)
			)
			(layer "B.Fab")
		)
		(fp_line
			(start 0.12065 0.3048)
			(end 0.67945 0.3048)
			(stroke
				(width 0.1)
				(type default)
			)
			(layer "B.Fab")
		)
		(fp_line
			(start 0.67945 -0.305054)
			(end 0.12065 -0.305054)
			(stroke
				(width 0.1)
				(type default)
			)
			(layer "B.Fab")
		)
		(fp_line
			(start 0.67945 0.3048)
			(end 0.67945 -0.305054)
			(stroke
				(width 0.1)
				(type default)
			)
			(layer "B.Fab")
		)
		(pad "1" smd circle
			(at 0.40005 0 180)
			(size 0 0)
			(layers "B.Cu" "B.Mask" "B.Paste")
			(net "NIC7_BIF2_N")
		)
		(pad "2" smd circle
			(at -0.40005 0 180)
			(size 0 0)
			(layers "B.Cu" "B.Mask" "B.Paste")
			(net "P3V3_AUX")
		)
	)
	(footprint ""
		(layer "B.Cu")
		(at 266.67968 -78.855316)
		(property "Reference" "L8"
			(at 0 0 0)
			(layer "B.SilkS")
			(hide yes)
			(effects
				(font
					(size 1.27 1.27)
				)
				(justify mirror)
			)
		)
		(property "Value" ""
			(at 0 0 0)
			(layer "B.Fab")
			(effects
				(font
					(size 1.27 1.27)
				)
				(justify mirror)
			)
		)
		(duplicate_pad_numbers_are_jumpers no)
		(fp_line
			(start -1.63576 -0.8128)
			(end -1.63576 0.8128)
			(stroke
				(width 0.1524)
				(type default)
			)
			(layer "B.SilkS")
		)
		(fp_line
			(start -1.63576 0.8128)
			(end 1.63576 0.8128)
			(stroke
				(width 0.1524)
				(type default)
			)
			(layer "B.SilkS")
		)
		(fp_line
			(start 1.63576 -0.8128)
			(end -1.63576 -0.8128)
			(stroke
				(width 0.1524)
				(type default)
			)
			(layer "B.SilkS")
		)
		(fp_line
			(start 1.63576 -0.8128)
			(end 1.63576 0.8128)
			(stroke
				(width 0.1524)
				(type default)
			)
			(layer "B.SilkS")
		)
		(fp_line
			(start -1.560576 -0.738632)
			(end 1.56083 -0.738632)
			(stroke
				(width 0.1)
				(type default)
			)
			(layer "B.Fab")
		)
		(fp_line
			(start -1.560576 0.7366)
			(end -1.560576 -0.738632)
			(stroke
				(width 0.1)
				(type default)
			)
			(layer "B.Fab")
		)
		(fp_line
			(start -1.524 0.7366)
			(end -1.560576 0.7366)
			(stroke
				(width 0.1)
				(type default)
			)
			(layer "B.Fab")
		)
		(fp_line
			(start 1.524 0.7366)
			(end -1.524 0.7366)
			(stroke
				(width 0.1)
				(type default)
			)
			(layer "B.Fab")
		)
		(fp_line
			(start 1.56083 -0.738632)
			(end 1.56083 0.7366)
			(stroke
				(width 0.1)
				(type default)
			)
			(layer "B.Fab")
		)
		(fp_line
			(start 1.56083 0.7366)
			(end 1.524 0.7366)
			(stroke
				(width 0.1)
				(type default)
			)
			(layer "B.Fab")
		)
		(pad "1" smd rect
			(at 0.94996 0)
			(size 1.1176 1.3716)
			(layers "B.Cu" "B.Mask" "B.Paste")
			(net "P3V3")
		)
		(pad "2" smd rect
			(at -0.94996 0)
			(size 1.1176 1.3716)
			(layers "B.Cu" "B.Mask" "B.Paste")
			(net "P3V3_CLK_GEN_VDD_CK440")
		)
	)
	(footprint ""
		(layer "B.Cu")
		(at 213.106 -194.183 -90)
		(property "Reference" "R6312"
			(at 0 0 90)
			(layer "B.SilkS")
			(hide yes)
			(effects
				(font
					(size 1.27 1.27)
				)
				(justify mirror)
			)
		)
		(property "Value" ""
			(at 0 0 90)
			(layer "B.Fab")
			(effects
				(font
					(size 1.27 1.27)
				)
				(justify mirror)
			)
		)
		(duplicate_pad_numbers_are_jumpers no)
		(fp_line
			(start -0.7874 0.4064)
			(end 0.7874 0.4064)
			(stroke
				(width 0.1524)
				(type default)
			)
			(layer "B.SilkS")
		)
		(fp_line
			(start 0.7874 0.4064)
			(end 0.7874 -0.4064)
			(stroke
				(width 0.1524)
				(type default)
			)
			(layer "B.SilkS")
		)
		(fp_line
			(start -0.7874 -0.4064)
			(end -0.7874 0.4064)
			(stroke
				(width 0.1524)
				(type default)
			)
			(layer "B.SilkS")
		)
		(fp_line
			(start 0.7874 -0.4064)
			(end -0.7874 -0.4064)
			(stroke
				(width 0.1524)
				(type default)
			)
			(layer "B.SilkS")
		)
		(fp_line
			(start -0.67945 0.3048)
			(end -0.120396 0.3048)
			(stroke
				(width 0.1)
				(type default)
			)
			(layer "B.Fab")
		)
		(fp_line
			(start -0.120396 0.3048)
			(end -0.120396 0.2794)
			(stroke
				(width 0.1)
				(type default)
			)
			(layer "B.Fab")
		)
		(fp_line
			(start 0.12065 0.3048)
			(end 0.67945 0.3048)
			(stroke
				(width 0.1)
				(type default)
			)
			(layer "B.Fab")
		)
		(fp_line
			(start 0.67945 0.3048)
			(end 0.67945 -0.305054)
			(stroke
				(width 0.1)
				(type default)
			)
			(layer "B.Fab")
		)
		(fp_line
			(start -0.120396 0.2794)
			(end 0.12065 0.2794)
			(stroke
				(width 0.1)
				(type default)
			)
			(layer "B.Fab")
		)
		(fp_line
			(start 0.12065 0.2794)
			(end 0.12065 0.3048)
			(stroke
				(width 0.1)
				(type default)
			)
			(layer "B.Fab")
		)
		(fp_line
			(start -0.12065 -0.2794)
			(end -0.12065 -0.3048)
			(stroke
				(width 0.1)
				(type default)
			)
			(layer "B.Fab")
		)
		(fp_line
			(start 0.12065 -0.2794)
			(end -0.12065 -0.2794)
			(stroke
				(width 0.1)
				(type default)
			)
			(layer "B.Fab")
		)
		(fp_line
			(start -0.67945 -0.3048)
			(end -0.67945 0.3048)
			(stroke
				(width 0.1)
				(type default)
			)
			(layer "B.Fab")
		)
		(fp_line
			(start -0.12065 -0.3048)
			(end -0.67945 -0.3048)
			(stroke
				(width 0.1)
				(type default)
			)
			(layer "B.Fab")
		)
		(fp_line
			(start 0.12065 -0.305054)
			(end 0.12065 -0.2794)
			(stroke
				(width 0.1)
				(type default)
			)
			(layer "B.Fab")
		)
		(fp_line
			(start 0.67945 -0.305054)
			(end 0.12065 -0.305054)
			(stroke
				(width 0.1)
				(type default)
			)
			(layer "B.Fab")
		)
		(pad "1" smd circle
			(at 0.40005 0 90)
			(size 0 0)
			(layers "B.Cu" "B.Mask" "B.Paste")
			(net "SMB_NIC7_LS_SDA")
		)
		(pad "2" smd circle
			(at -0.40005 0 90)
			(size 0 0)
			(layers "B.Cu" "B.Mask" "B.Paste")
			(net "SMB_NIC7_LS_R_SDA")
		)
	)
)
